(kicad_pcb
	(version 20240108)
	(generator "pcbnew")
	(generator_version "8.0")
	(general
		(thickness 1.62)
		(legacy_teardrops no)
	)
	(paper "A4")
	(title_block
		(title "Jetson Orin Baseboard")
		(date "2025-03-12")
		(rev "1.3.4")
		(company "Antmicro Ltd")
		(comment 1 "www.antmicro.com")
		(comment 9 "footprints 170-173 of 677")
	)
	(layers
		(0 "F.Cu" signal)
		(1 "In1.Cu" signal)
		(2 "In2.Cu" signal)
		(3 "In3.Cu" signal)
		(4 "In4.Cu" jumper)
		(5 "In5.Cu" signal)
		(6 "In6.Cu" signal)
		(31 "B.Cu" signal)
		(32 "B.Adhes" user "B.Adhesive")
		(33 "F.Adhes" user "F.Adhesive")
		(34 "B.Paste" user)
		(35 "F.Paste" user)
		(36 "B.SilkS" user "B.Silkscreen")
		(37 "F.SilkS" user "F.Silkscreen")
		(38 "B.Mask" user)
		(39 "F.Mask" user)
		(40 "Dwgs.User" user "User.Drawings")
		(41 "Cmts.User" user "User.Comments")
		(42 "Eco1.User" user "User.Eco1")
		(43 "Eco2.User" user "User.Eco2")
		(44 "Edge.Cuts" user)
		(45 "Margin" user)
		(46 "B.CrtYd" user "B.Courtyard")
		(47 "F.CrtYd" user "F.Courtyard")
		(48 "B.Fab" user)
		(49 "F.Fab" user)
	)
	(footprint "antmicro-footprints:C_0402_1005Metric"
		(layer "F.Cu")
		(at 137.4 113.1)
		(descr "Capacitor SMD 0402")
		(tags "capacitor SMD 0402")
		(property "Reference" "C106"
			(at -5.84 0.27 0)
			(layer "F.SilkS")
			(effects
				(font
					(size 0.7 0.7)
					(thickness 0.15)
				)
				(justify left bottom)
			)
		)
		(property "Value" "C_1u_0402"
			(at 0 1.4 0)
			(layer "F.Fab")
			(effects
				(font
					(size 0.7 0.7)
					(thickness 0.15)
				)
				(justify left bottom)
			)
		)
		(property "Footprint" "antmicro-footprints:C_0402_1005Metric"
			(at 0 0 0)
			(layer "F.Fab")
			(hide yes)
			(effects
				(font
					(size 1.27 1.27)
					(thickness 0.15)
				)
			)
		)
		(property "Datasheet" "https://product.tdk.com/en/search/capacitor/ceramic/mlcc/info?part_no=C1005X6S1A105K050BC"
			(at 0 0 0)
			(layer "F.Fab")
			(hide yes)
			(effects
				(font
					(size 1.27 1.27)
					(thickness 0.15)
				)
			)
		)
		(property "Author" "Antmicro"
			(at 0 0 0)
			(layer "F.Fab")
			(hide yes)
			(effects
				(font
					(size 1 1)
					(thickness 0.15)
				)
			)
		)
		(property "Dielectric" ""
			(at 0 0 0)
			(layer "F.Fab")
			(hide yes)
			(effects
				(font
					(size 1 1)
					(thickness 0.15)
				)
			)
		)
		(property "License" "Apache-2.0"
			(at 0 0 0)
			(layer "F.Fab")
			(hide yes)
			(effects
				(font
					(size 1 1)
					(thickness 0.15)
				)
			)
		)
		(property "MPN" "C1005X6S1A105K050BC"
			(at 0 0 0)
			(layer "F.Fab")
			(hide yes)
			(effects
				(font
					(size 1 1)
					(thickness 0.15)
				)
			)
		)
		(property "Manufacturer" "TDK"
			(at 0 0 0)
			(layer "F.Fab")
			(hide yes)
			(effects
				(font
					(size 1 1)
					(thickness 0.15)
				)
			)
		)
		(property "Val" "1u"
			(at 0 0 0)
			(layer "F.Fab")
			(hide yes)
			(effects
				(font
					(size 1 1)
					(thickness 0.15)
				)
			)
		)
		(property "Voltage" ""
			(at 0 0 0)
			(layer "F.Fab")
			(hide yes)
			(effects
				(font
					(size 1 1)
					(thickness 0.15)
				)
			)
		)
		(sheetname "Peripherals")
		(sheetfile "peripherals.kicad_sch")
		(attr smd)
		(fp_rect
			(start -0.925 -0.47)
			(end 0.925 0.47)
			(stroke
				(width 0.05)
				(type default)
			)
			(fill none)
			(layer "F.CrtYd")
		)
		(fp_line
			(start -0.494 -0.25)
			(end 0.504 -0.25)
			(stroke
				(width 0.15)
				(type solid)
			)
			(layer "F.Fab")
		)
		(fp_line
			(start -0.494 0.248)
			(end -0.494 -0.25)
			(stroke
				(width 0.15)
				(type solid)
			)
			(layer "F.Fab")
		)
		(fp_line
			(start 0.504 -0.25)
			(end 0.504 0.248)
			(stroke
				(width 0.15)
				(type solid)
			)
			(layer "F.Fab")
		)
		(fp_line
			(start 0.504 0.248)
			(end -0.494 0.248)
			(stroke
				(width 0.15)
				(type solid)
			)
			(layer "F.Fab")
		)
		(fp_text user "License: Apache-2.0"
			(at -0.932 5.17 0)
			(layer "F.Fab")
			(hide yes)
			(effects
				(font
					(size 0.7 0.7)
					(thickness 0.15)
				)
				(justify left bottom)
			)
		)
		(fp_text user "Author: Antmicro"
			(at -0.932 4.17 0)
			(layer "F.Fab")
			(hide yes)
			(effects
				(font
					(size 0.7 0.7)
					(thickness 0.15)
				)
				(justify left bottom)
			)
		)
		(fp_text user "${REFERENCE}"
			(at -0.932 3.168 0)
			(layer "F.Fab")
			(hide yes)
			(effects
				(font
					(size 0.7 0.7)
					(thickness 0.15)
				)
				(justify left bottom)
			)
		)
		(pad "1" smd roundrect
			(at -0.48 0)
			(size 0.59 0.64)
			(layers "F.Cu" "F.Paste" "F.Mask")
			(roundrect_rratio 0.25)
			(net 1 "GND")
			(pintype "passive")
		)
		(pad "2" smd roundrect
			(at 0.48 0)
			(size 0.59 0.64)
			(layers "F.Cu" "F.Paste" "F.Mask")
			(roundrect_rratio 0.25)
			(net 483 "/Peripherals/1V8_CONN")
			(pintype "passive")
		)
	)
	(footprint "antmicro-footprints:SOT-523"
		(layer "F.Cu")
		(at 105.4 118.85 90)
		(property "Reference" "Q4"
			(at 1.125 -0.65 0)
			(layer "F.SilkS")
			(effects
				(font
					(size 0.7 0.7)
					(thickness 0.15)
				)
				(justify left bottom)
			)
		)
		(property "Value" "PJE138K"
			(at 0.1 1.824 90)
			(layer "F.Fab")
			(effects
				(font
					(size 0.7 0.7)
					(thickness 0.15)
				)
				(justify left bottom)
			)
		)
		(property "Footprint" "antmicro-footprints:SOT-523"
			(at 0 0 90)
			(layer "F.Fab")
			(hide yes)
			(effects
				(font
					(size 1.27 1.27)
					(thickness 0.15)
				)
			)
		)
		(property "Datasheet" "https://www.mouser.com/datasheet/2/1057/PJE138K-1876698.pdf"
			(at 0 0 90)
			(layer "F.Fab")
			(hide yes)
			(effects
				(font
					(size 1.27 1.27)
					(thickness 0.15)
				)
			)
		)
		(property "Author" "Antmicro"
			(at 224.25 13.45 0)
			(layer "F.Fab")
			(hide yes)
			(effects
				(font
					(size 1 1)
					(thickness 0.15)
				)
			)
		)
		(property "License" "Apache-2.0"
			(at 224.25 13.45 0)
			(layer "F.Fab")
			(hide yes)
			(effects
				(font
					(size 1 1)
					(thickness 0.15)
				)
			)
		)
		(property "MPN" "PJE138K_R1_00001"
			(at 224.25 13.45 0)
			(layer "F.Fab")
			(hide yes)
			(effects
				(font
					(size 1 1)
					(thickness 0.15)
				)
			)
		)
		(property "Manufacturer" "PANJIT"
			(at 224.25 13.45 0)
			(layer "F.Fab")
			(hide yes)
			(effects
				(font
					(size 1 1)
					(thickness 0.15)
				)
			)
		)
		(sheetname "USB3")
		(sheetfile "usb3.kicad_sch")
		(attr smd)
		(fp_line
			(start -0.277 -0.551)
			(end -0.277 -0.75)
			(stroke
				(width 0.15)
				(type solid)
			)
			(layer "F.SilkS")
		)
		(fp_line
			(start -0.725 -0.551)
			(end -0.277 -0.551)
			(stroke
				(width 0.15)
				(type solid)
			)
			(layer "F.SilkS")
		)
		(fp_line
			(start -0.927 -0.351)
			(end -0.725 -0.551)
			(stroke
				(width 0.15)
				(type solid)
			)
			(layer "F.SilkS")
		)
		(fp_line
			(start -0.927 -0.051)
			(end -0.927 -0.351)
			(stroke
				(width 0.15)
				(type solid)
			)
			(layer "F.SilkS")
		)
		(fp_circle
			(center -0.9652 0.9652)
			(end -0.9152 0.9652)
			(stroke
				(width 0.15)
				(type solid)
			)
			(fill solid)
			(layer "F.SilkS")
		)
		(fp_line
			(start 1.1 -1.16)
			(end 1.1 1.15)
			(stroke
				(width 0.05)
				(type solid)
			)
			(layer "F.CrtYd")
		)
		(fp_line
			(start -1.12 -1.16)
			(end 1.1 -1.16)
			(stroke
				(width 0.05)
				(type solid)
			)
			(layer "F.CrtYd")
		)
		(fp_line
			(start -1.12 -1.16)
			(end -1.12 1.15)
			(stroke
				(width 0.05)
				(type solid)
			)
			(layer "F.CrtYd")
		)
		(fp_line
			(start -1.12 1.15)
			(end 1.1 1.15)
			(stroke
				(width 0.05)
				(type solid)
			)
			(layer "F.CrtYd")
		)
		(fp_line
			(start 0.8 -0.425)
			(end -0.652 -0.425)
			(stroke
				(width 0.15)
				(type solid)
			)
			(layer "F.Fab")
		)
		(fp_line
			(start 0.8 -0.425)
			(end 0.8 0.424)
			(stroke
				(width 0.15)
				(type solid)
			)
			(layer "F.Fab")
		)
		(fp_line
			(start -0.652 -0.425)
			(end -0.802 -0.276)
			(stroke
				(width 0.15)
				(type solid)
			)
			(layer "F.Fab")
		)
		(fp_line
			(start -0.802 -0.276)
			(end -0.802 0.424)
			(stroke
				(width 0.15)
				(type solid)
			)
			(layer "F.Fab")
		)
		(fp_line
			(start 0.8 0.424)
			(end -0.802 0.424)
			(stroke
				(width 0.15)
				(type solid)
			)
			(layer "F.Fab")
		)
		(fp_circle
			(center -0.9652 0.9652)
			(end -0.9144 0.9652)
			(stroke
				(width 0.15)
				(type solid)
			)
			(fill none)
			(layer "F.Fab")
		)
		(fp_text user "Author: Antmicro"
			(at -1.12 6.224 90)
			(layer "F.Fab")
			(hide yes)
			(effects
				(font
					(size 0.7 0.7)
					(thickness 0.15)
				)
				(justify left bottom)
			)
		)
		(fp_text user "${REFERENCE}"
			(at -1.12 3.824 90)
			(layer "F.Fab")
			(hide yes)
			(effects
				(font
					(size 0.7 0.7)
					(thickness 0.15)
				)
				(justify left bottom)
			)
		)
		(fp_text user "License: Apache-2.0"
			(at -1.12 5.024 90)
			(layer "F.Fab")
			(hide yes)
			(effects
				(font
					(size 0.7 0.7)
					(thickness 0.15)
				)
				(justify left bottom)
			)
		)
		(pad "1" smd rect
			(at -0.5 0.65 90)
			(size 0.4 0.51)
			(layers "F.Cu" "F.Paste" "F.Mask")
			(net 284 "/USB3/USBC1_ID")
			(pinfunction "G")
			(pintype "passive")
		)
		(pad "2" smd rect
			(at 0.498 0.65 90)
			(size 0.4 0.51)
			(layers "F.Cu" "F.Paste" "F.Mask")
			(net 1 "GND")
			(pinfunction "S")
			(pintype "passive")
		)
		(pad "3" smd rect
			(at 0 -0.652 90)
			(size 0.4 0.51)
			(layers "F.Cu" "F.Paste" "F.Mask")
			(net 625 "Net-(Q4-D)")
			(pinfunction "D")
			(pintype "passive")
		)
	)
	(footprint "antmicro-footprints:LED_0603_1608Metric_G"
		(layer "F.Cu")
		(at 30.775 105.025 -90)
		(descr "LED SMD 0603 Green")
		(tags "LED SMD 0603 Green")
		(property "Reference" "D15"
			(at 1.075 -0.025 -90)
			(layer "F.SilkS")
			(effects
				(font
					(size 0.7 0.7)
					(thickness 0.15)
				)
				(justify right bottom)
			)
		)
		(property "Value" "LED_G_0603_LTST-C190GKT"
			(at -0.001 1.599 90)
			(layer "F.Fab")
			(effects
				(font
					(size 0.7 0.7)
					(thickness 0.15)
				)
				(justify right bottom)
			)
		)
		(property "Footprint" "antmicro-footprints:LED_0603_1608Metric_G"
			(at 0 0 -90)
			(layer "F.Fab")
			(hide yes)
			(effects
				(font
					(size 1.27 1.27)
					(thickness 0.15)
				)
			)
		)
		(property "Datasheet" "https://media.digikey.com/pdf/Data%20Sheets/Lite-On%20PDFs/LTST-C190GKT.pdf"
			(at 0 0 -90)
			(layer "F.Fab")
			(hide yes)
			(effects
				(font
					(size 1.27 1.27)
					(thickness 0.15)
				)
			)
		)
		(property "Author" "Antmicro"
			(at -74.25 135.8 0)
			(layer "F.Fab")
			(hide yes)
			(effects
				(font
					(size 1 1)
					(thickness 0.15)
				)
			)
		)
		(property "Color" "Green"
			(at -74.25 135.8 0)
			(layer "F.Fab")
			(hide yes)
			(effects
				(font
					(size 1 1)
					(thickness 0.15)
				)
			)
		)
		(property "License" "Apache-2.0"
			(at -74.25 135.8 0)
			(layer "F.Fab")
			(hide yes)
			(effects
				(font
					(size 1 1)
					(thickness 0.15)
				)
			)
		)
		(property "MPN" "LTST-C190GKT"
			(at -74.25 135.8 0)
			(layer "F.Fab")
			(hide yes)
			(effects
				(font
					(size 1 1)
					(thickness 0.15)
				)
			)
		)
		(property "Manufacturer" "Lite-On"
			(at -74.25 135.8 0)
			(layer "F.Fab")
			(hide yes)
			(effects
				(font
					(size 1 1)
					(thickness 0.15)
				)
			)
		)
		(sheetname "Ethernet")
		(sheetfile "ethernet.kicad_sch")
		(attr smd)
		(fp_line
			(start 0.22 0.35)
			(end -0.22 0.35)
			(stroke
				(width 0.15)
				(type solid)
			)
			(layer "F.SilkS")
		)
		(fp_line
			(start -0.094672 0.201008)
			(end -0.094672 -0.198992)
			(stroke
				(width 0.1)
				(type solid)
			)
			(layer "F.SilkS")
		)
		(fp_line
			(start 0.105328 0.201008)
			(end -0.094672 0.001008)
			(stroke
				(width 0.1)
				(type solid)
			)
			(layer "F.SilkS")
		)
		(fp_line
			(start 0.105328 0.201008)
			(end 0.105328 -0.198992)
			(stroke
				(width 0.1)
				(type solid)
			)
			(layer "F.SilkS")
		)
		(fp_line
			(start -0.094672 0.001008)
			(end -0.24 0.001008)
			(stroke
				(width 0.1)
				(type solid)
			)
			(layer "F.SilkS")
		)
		(fp_line
			(start -0.094672 0.001008)
			(end 0.105328 -0.198992)
			(stroke
				(width 0.1)
				(type solid)
			)
			(layer "F.SilkS")
		)
		(fp_line
			(start 0.105328 0.001008)
			(end 0.24 0.001)
			(stroke
				(width 0.1)
				(type solid)
			)
			(layer "F.SilkS")
		)
		(fp_line
			(start -1.18 -0.319)
			(end -1.18 0.321)
			(stroke
				(width 0.15)
				(type solid)
			)
			(layer "F.SilkS")
		)
		(fp_line
			(start 0.22 -0.35)
			(end -0.22 -0.35)
			(stroke
				(width 0.15)
				(type solid)
			)
			(layer "F.SilkS")
		)
		(fp_rect
			(start 1.25 0.65)
			(end -1.25 -0.65)
			(stroke
				(width 0.05)
				(type solid)
			)
			(fill none)
			(layer "F.CrtYd")
		)
		(fp_line
			(start -0.199 0.2)
			(end -0.199 0.1)
			(stroke
				(width 0.15)
				(type solid)
			)
			(layer "F.Fab")
		)
		(fp_line
			(start 0.201 0.2)
			(end 0.201 0)
			(stroke
				(width 0.15)
				(type solid)
			)
			(layer "F.Fab")
		)
		(fp_line
			(start -0.199 0)
			(end -0.597 0)
			(stroke
				(width 0.15)
				(type solid)
			)
			(layer "F.Fab")
		)
		(fp_line
			(start -0.101 0)
			(end 0.201 0.2)
			(stroke
				(width 0.15)
				(type solid)
			)
			(layer "F.Fab")
		)
		(fp_line
			(start 0.201 0)
			(end 0.201 -0.202)
			(stroke
				(width 0.15)
				(type solid)
			)
			(layer "F.Fab")
		)
		(fp_line
			(start 0.599 0)
			(end 0.201 0)
			(stroke
				(width 0.15)
				(type solid)
			)
			(layer "F.Fab")
		)
		(fp_line
			(start -0.199 -0.202)
			(end -0.199 0.1)
			(stroke
				(width 0.15)
				(type solid)
			)
			(layer "F.Fab")
		)
		(fp_line
			(start 0.201 -0.202)
			(end -0.101 0)
			(stroke
				(width 0.15)
				(type solid)
			)
			(layer "F.Fab")
		)
		(fp_rect
			(start 0.848 0.4)
			(end -0.85 -0.402)
			(stroke
				(width 0.15)
				(type solid)
			)
			(fill none)
			(layer "F.Fab")
		)
		(fp_text user "${REFERENCE}"
			(at -1.4224 5.999 90)
			(layer "F.Fab")
			(hide yes)
			(effects
				(font
					(size 0.7 0.7)
					(thickness 0.15)
				)
				(justify right bottom)
			)
		)
		(fp_text user "License: Apache-2.0"
			(at -1.4224 3.599 90)
			(layer "F.Fab")
			(hide yes)
			(effects
				(font
					(size 0.7 0.7)
					(thickness 0.15)
				)
				(justify right bottom)
			)
		)
		(fp_text user "Author: Antmicro"
			(at -1.4224 4.799 90)
			(layer "F.Fab")
			(hide yes)
			(effects
				(font
					(size 0.7 0.7)
					(thickness 0.15)
				)
				(justify right bottom)
			)
		)
		(pad "1" smd roundrect
			(at -0.7 0 90)
			(size 0.8 1)
			(layers "F.Cu" "F.Paste" "F.Mask")
			(roundrect_rratio 0.2)
			(net 106 "GNDD")
			(pinfunction "C")
			(pintype "passive")
		)
		(pad "2" smd roundrect
			(at 0.7 0 90)
			(size 0.8 1)
			(layers "F.Cu" "F.Paste" "F.Mask")
			(roundrect_rratio 0.2)
			(net 153 "Net-(D15-A)")
			(pinfunction "A")
			(pintype "passive")
		)
	)
	(footprint "antmicro-footprints:R_0402_1005Metric"
		(layer "F.Cu")
		(at 75.42 85.34)
		(descr "Resistor SMD 0402")
		(tags "resistor SMD 0402")
		(property "Reference" "R176"
			(at -2.12 -2.3 0)
			(layer "F.SilkS")
			(effects
				(font
					(size 0.7 0.7)
					(thickness 0.15)
				)
				(justify left bottom)
			)
		)
		(property "Value" "R_499k_0402"
			(at -1.011843 1.772047 0)
			(layer "F.Fab")
			(effects
				(font
					(size 0.7 0.7)
					(thickness 0.15)
				)
				(justify left bottom)
			)
		)
		(property "Footprint" "antmicro-footprints:R_0402_1005Metric"
			(at 0 0 0)
			(layer "F.Fab")
			(hide yes)
			(effects
				(font
					(size 1.27 1.27)
					(thickness 0.15)
				)
			)
		)
		(property "Datasheet" "https://www.mouser.com/datasheet/2/54/cr-1858361.pdf"
			(at 0 0 0)
			(layer "F.Fab")
			(hide yes)
			(effects
				(font
					(size 1.27 1.27)
					(thickness 0.15)
				)
			)
		)
		(property "Author" "Antmicro"
			(at 0 0 0)
			(layer "F.Fab")
			(hide yes)
			(effects
				(font
					(size 1 1)
					(thickness 0.15)
				)
			)
		)
		(property "License" "Apache-2.0"
			(at 0 0 0)
			(layer "F.Fab")
			(hide yes)
			(effects
				(font
					(size 1 1)
					(thickness 0.15)
				)
			)
		)
		(property "MPN" "CR0402-FX-4993GLF"
			(at 0 0 0)
			(layer "F.Fab")
			(hide yes)
			(effects
				(font
					(size 1 1)
					(thickness 0.15)
				)
			)
		)
		(property "Manufacturer" "Bourns"
			(at 0 0 0)
			(layer "F.Fab")
			(hide yes)
			(effects
				(font
					(size 1 1)
					(thickness 0.15)
				)
			)
		)
		(property "Tolerance" "1%"
			(at 0 0 0)
			(layer "F.Fab")
			(hide yes)
			(effects
				(font
					(size 1 1)
					(thickness 0.15)
				)
			)
		)
		(property "Val" "499k"
			(at 0 0 0)
			(layer "F.Fab")
			(hide yes)
			(effects
				(font
					(size 1 1)
					(thickness 0.15)
				)
			)
		)
		(sheetname "Supply")
		(sheetfile "supply.kicad_sch")
		(attr smd)
		(fp_rect
			(start -0.925 -0.47)
			(end 0.925 0.47)
			(stroke
				(width 0.05)
				(type default)
			)
			(fill none)
			(layer "F.CrtYd")
		)
		(fp_rect
			(start -0.5 -0.25)
			(end 0.5 0.25)
			(stroke
				(width 0.15)
				(type solid)
			)
			(fill none)
			(layer "F.Fab")
		)
		(fp_text user "${REFERENCE}"
			(at -0.95 3.168 0)
			(layer "F.Fab")
			(hide yes)
			(effects
				(font
					(size 0.7 0.7)
					(thickness 0.15)
				)
				(justify left bottom)
			)
		)
		(fp_text user "License: Apache-2.0"
			(at -0.95 5.169 0)
			(layer "F.Fab")
			(hide yes)
			(effects
				(font
					(size 0.7 0.7)
					(thickness 0.15)
				)
				(justify left bottom)
			)
		)
		(fp_text user "Author: Antmicro"
			(at -0.95 4.169 0)
			(layer "F.Fab")
			(hide yes)
			(effects
				(font
					(size 0.7 0.7)
					(thickness 0.15)
				)
				(justify left bottom)
			)
		)
		(pad "1" smd roundrect
			(at -0.48 0)
			(size 0.59 0.64)
			(layers "F.Cu" "F.Paste" "F.Mask")
			(roundrect_rratio 0.25)
			(net 1 "GND")
			(pintype "passive")
		)
		(pad "2" smd roundrect
			(at 0.48 0)
			(size 0.59 0.64)
			(layers "F.Cu" "F.Paste" "F.Mask")
			(roundrect_rratio 0.25)
			(net 687 "/Supply/3V3_MODE1")
			(pintype "passive")
		)
	)
)
